(kicad_pcb
	(version 20260206)
	(generator "pcbnew")
	(generator_version "10.0")
	(general
		(thickness 1.6)
		(legacy_teardrops no)
	)
	(paper "A4")
	(title_block
		(title "04192023_DAF0TMB3IC0_F0TG_MB_C_brd_V02_OCP.brd")
		(comment 1 "Grand Teton / footprints 6266-6273 of 8354")
	)
	(layers
		(0 "F.Cu" signal "TOP")
		(4 "In1.Cu" signal "GND")
		(6 "In2.Cu" signal "IN1")
		(8 "In3.Cu" signal "GND1")
		(10 "In4.Cu" signal "IN2")
		(12 "In5.Cu" signal "GND2")
		(14 "In6.Cu" signal "IN3")
		(16 "In7.Cu" signal "GND3")
		(18 "In8.Cu" signal "VCC")
		(20 "In9.Cu" signal "VCC1")
		(22 "In10.Cu" signal "GND4")
		(24 "In11.Cu" signal "IN4")
		(26 "In12.Cu" signal "GND5")
		(28 "In13.Cu" signal "IN5")
		(30 "In14.Cu" signal "GND6")
		(32 "In15.Cu" signal "IN6")
		(34 "In16.Cu" signal "GND7")
		(2 "B.Cu" signal "BOTTOM")
		(9 "F.Adhes" user "F.Adhesive")
		(11 "B.Adhes" user "B.Adhesive")
		(13 "F.Paste" user "Package Geometry/Pastemask Top")
		(15 "B.Paste" user "Package Geometry/Pastemask Bottom")
		(5 "F.SilkS" user "Ref Des/Silkscreen Top")
		(7 "B.SilkS" user "Ref Des/Silkscreen Bottom")
		(1 "F.Mask" user "Board Geometry/Soldermask Top")
		(3 "B.Mask" user "Board Geometry/Soldermask Bottom")
		(17 "Dwgs.User" user "User.Drawings")
		(19 "Cmts.User" user "User.Comments")
		(21 "Eco1.User" user "User.Eco1")
		(23 "Eco2.User" user "User.Eco2")
		(25 "Edge.Cuts" user "Board Geometry/Outline")
		(27 "Margin" user)
		(31 "F.CrtYd" user "Package Geometry/Place Bound Top")
		(29 "B.CrtYd" user "Package Geometry/Place Bound Bottom")
		(35 "F.Fab" user "Ref Des/Assembly Top")
		(33 "B.Fab" user "Ref Des/Assembly Bottom")
	)
	(footprint ""
		(layer "B.Cu")
		(at 138.65352 -38.733222 180)
		(property "Reference" "C6058"
			(at 0 0 0)
			(layer "B.SilkS")
			(hide yes)
			(effects
				(font
					(size 1.27 1.27)
				)
				(justify mirror)
			)
		)
		(property "Value" ""
			(at 0 0 0)
			(layer "B.Fab")
			(effects
				(font
					(size 1.27 1.27)
				)
				(justify mirror)
			)
		)
		(duplicate_pad_numbers_are_jumpers no)
		(fp_line
			(start 0.7874 0.4064)
			(end 0.7874 -0.4064)
			(stroke
				(width 0.1524)
				(type default)
			)
			(layer "B.SilkS")
		)
		(fp_line
			(start 0.7874 -0.4064)
			(end -0.7874 -0.4064)
			(stroke
				(width 0.1524)
				(type default)
			)
			(layer "B.SilkS")
		)
		(fp_line
			(start -0.7874 0.4064)
			(end 0.7874 0.4064)
			(stroke
				(width 0.1524)
				(type default)
			)
			(layer "B.SilkS")
		)
		(fp_line
			(start -0.7874 -0.4064)
			(end -0.7874 0.4064)
			(stroke
				(width 0.1524)
				(type default)
			)
			(layer "B.SilkS")
		)
		(fp_line
			(start 0.67945 0.3048)
			(end 0.67945 -0.305054)
			(stroke
				(width 0.1)
				(type default)
			)
			(layer "B.Fab")
		)
		(fp_line
			(start 0.67945 -0.305054)
			(end 0.12065 -0.305054)
			(stroke
				(width 0.1)
				(type default)
			)
			(layer "B.Fab")
		)
		(fp_line
			(start 0.12065 0.3048)
			(end 0.67945 0.3048)
			(stroke
				(width 0.1)
				(type default)
			)
			(layer "B.Fab")
		)
		(fp_line
			(start 0.12065 0.2794)
			(end 0.12065 0.3048)
			(stroke
				(width 0.1)
				(type default)
			)
			(layer "B.Fab")
		)
		(fp_line
			(start 0.12065 -0.2794)
			(end -0.12065 -0.2794)
			(stroke
				(width 0.1)
				(type default)
			)
			(layer "B.Fab")
		)
		(fp_line
			(start 0.12065 -0.305054)
			(end 0.12065 -0.2794)
			(stroke
				(width 0.1)
				(type default)
			)
			(layer "B.Fab")
		)
		(fp_line
			(start -0.120396 0.3048)
			(end -0.120396 0.2794)
			(stroke
				(width 0.1)
				(type default)
			)
			(layer "B.Fab")
		)
		(fp_line
			(start -0.120396 0.2794)
			(end 0.12065 0.2794)
			(stroke
				(width 0.1)
				(type default)
			)
			(layer "B.Fab")
		)
		(fp_line
			(start -0.12065 -0.2794)
			(end -0.12065 -0.3048)
			(stroke
				(width 0.1)
				(type default)
			)
			(layer "B.Fab")
		)
		(fp_line
			(start -0.12065 -0.3048)
			(end -0.67945 -0.3048)
			(stroke
				(width 0.1)
				(type default)
			)
			(layer "B.Fab")
		)
		(fp_line
			(start -0.67945 0.3048)
			(end -0.120396 0.3048)
			(stroke
				(width 0.1)
				(type default)
			)
			(layer "B.Fab")
		)
		(fp_line
			(start -0.67945 -0.3048)
			(end -0.67945 0.3048)
			(stroke
				(width 0.1)
				(type default)
			)
			(layer "B.Fab")
		)
		(pad "1" smd circle
			(at 0.40005 0)
			(size 0 0)
			(layers "B.Cu" "B.Mask" "B.Paste")
			(net "P1V2_AUX")
		)
		(pad "2" smd circle
			(at -0.40005 0)
			(size 0 0)
			(layers "B.Cu" "B.Mask" "B.Paste")
			(net "GND")
		)
	)
	(footprint ""
		(layer "B.Cu")
		(at 74.5236 -385.58216 180)
		(property "Reference" "R784"
			(at 0 0 0)
			(layer "B.SilkS")
			(hide yes)
			(effects
				(font
					(size 1.27 1.27)
				)
				(justify mirror)
			)
		)
		(property "Value" ""
			(at 0 0 0)
			(layer "B.Fab")
			(effects
				(font
					(size 1.27 1.27)
				)
				(justify mirror)
			)
		)
		(duplicate_pad_numbers_are_jumpers no)
		(fp_line
			(start 0.32512 0.175006)
			(end 0.32512 -0.175006)
			(stroke
				(width 0.1)
				(type default)
			)
			(layer "B.Fab")
		)
		(fp_line
			(start 0.32512 -0.175006)
			(end -0.32512 -0.175006)
			(stroke
				(width 0.1)
				(type default)
			)
			(layer "B.Fab")
		)
		(fp_line
			(start -0.32512 0.175006)
			(end 0.32512 0.175006)
			(stroke
				(width 0.1)
				(type default)
			)
			(layer "B.Fab")
		)
		(fp_line
			(start -0.32512 -0.175006)
			(end -0.32512 0.175006)
			(stroke
				(width 0.1)
				(type default)
			)
			(layer "B.Fab")
		)
		(pad "1" smd rect
			(at 0.2667 0)
			(size 0.3048 0.381)
			(layers "B.Cu" "B.Mask" "B.Paste")
			(net "P1V8_CPU1_RT_1D")
		)
		(pad "2" smd rect
			(at -0.2667 0 180)
			(size 0.3048 0.381)
			(layers "B.Cu" "B.Mask" "B.Paste")
			(net "TEST0_RT_CPU1_P1")
		)
	)
	(footprint ""
		(layer "B.Cu")
		(at 43.576748 -195.901564 180)
		(property "Reference" "R1697"
			(at 0 0 0)
			(layer "B.SilkS")
			(hide yes)
			(effects
				(font
					(size 1.27 1.27)
				)
				(justify mirror)
			)
		)
		(property "Value" ""
			(at 0 0 0)
			(layer "B.Fab")
			(effects
				(font
					(size 1.27 1.27)
				)
				(justify mirror)
			)
		)
		(duplicate_pad_numbers_are_jumpers no)
		(fp_line
			(start 0.7874 0.4064)
			(end 0.7874 -0.4064)
			(stroke
				(width 0.1524)
				(type default)
			)
			(layer "B.SilkS")
		)
		(fp_line
			(start 0.7874 -0.4064)
			(end -0.7874 -0.4064)
			(stroke
				(width 0.1524)
				(type default)
			)
			(layer "B.SilkS")
		)
		(fp_line
			(start -0.7874 0.4064)
			(end 0.7874 0.4064)
			(stroke
				(width 0.1524)
				(type default)
			)
			(layer "B.SilkS")
		)
		(fp_line
			(start -0.7874 -0.4064)
			(end -0.7874 0.4064)
			(stroke
				(width 0.1524)
				(type default)
			)
			(layer "B.SilkS")
		)
		(fp_line
			(start 0.67945 0.3048)
			(end 0.67945 -0.305054)
			(stroke
				(width 0.1)
				(type default)
			)
			(layer "B.Fab")
		)
		(fp_line
			(start 0.67945 -0.305054)
			(end 0.12065 -0.305054)
			(stroke
				(width 0.1)
				(type default)
			)
			(layer "B.Fab")
		)
		(fp_line
			(start 0.12065 0.3048)
			(end 0.67945 0.3048)
			(stroke
				(width 0.1)
				(type default)
			)
			(layer "B.Fab")
		)
		(fp_line
			(start 0.12065 0.2794)
			(end 0.12065 0.3048)
			(stroke
				(width 0.1)
				(type default)
			)
			(layer "B.Fab")
		)
		(fp_line
			(start 0.12065 -0.2794)
			(end -0.12065 -0.2794)
			(stroke
				(width 0.1)
				(type default)
			)
			(layer "B.Fab")
		)
		(fp_line
			(start 0.12065 -0.305054)
			(end 0.12065 -0.2794)
			(stroke
				(width 0.1)
				(type default)
			)
			(layer "B.Fab")
		)
		(fp_line
			(start -0.120396 0.3048)
			(end -0.120396 0.2794)
			(stroke
				(width 0.1)
				(type default)
			)
			(layer "B.Fab")
		)
		(fp_line
			(start -0.120396 0.2794)
			(end 0.12065 0.2794)
			(stroke
				(width 0.1)
				(type default)
			)
			(layer "B.Fab")
		)
		(fp_line
			(start -0.12065 -0.2794)
			(end -0.12065 -0.3048)
			(stroke
				(width 0.1)
				(type default)
			)
			(layer "B.Fab")
		)
		(fp_line
			(start -0.12065 -0.3048)
			(end -0.67945 -0.3048)
			(stroke
				(width 0.1)
				(type default)
			)
			(layer "B.Fab")
		)
		(fp_line
			(start -0.67945 0.3048)
			(end -0.120396 0.3048)
			(stroke
				(width 0.1)
				(type default)
			)
			(layer "B.Fab")
		)
		(fp_line
			(start -0.67945 -0.3048)
			(end -0.67945 0.3048)
			(stroke
				(width 0.1)
				(type default)
			)
			(layer "B.Fab")
		)
		(pad "1" smd circle
			(at 0.40005 0)
			(size 0 0)
			(layers "B.Cu" "B.Mask" "B.Paste")
			(net "I3C_SPD_DDRAF_CPU1_SDA")
		)
		(pad "2" smd circle
			(at -0.40005 0)
			(size 0 0)
			(layers "B.Cu" "B.Mask" "B.Paste")
			(net "I3C_SPD_DDRC_CPU1_SDA")
		)
	)
	(footprint ""
		(layer "B.Cu")
		(at 273.092164 -192.660016 180)
		(property "Reference" "C153"
			(at 0 0 0)
			(layer "B.SilkS")
			(hide yes)
			(effects
				(font
					(size 1.27 1.27)
				)
				(justify mirror)
			)
		)
		(property "Value" ""
			(at 0 0 0)
			(layer "B.Fab")
			(effects
				(font
					(size 1.27 1.27)
				)
				(justify mirror)
			)
		)
		(duplicate_pad_numbers_are_jumpers no)
		(fp_line
			(start 1.524 0.762)
			(end 1.524 -0.762)
			(stroke
				(width 0.1524)
				(type default)
			)
			(layer "B.SilkS")
		)
		(fp_line
			(start 1.524 -0.762)
			(end -1.524 -0.762)
			(stroke
				(width 0.1524)
				(type default)
			)
			(layer "B.SilkS")
		)
		(fp_line
			(start -1.524 0.762)
			(end 1.524 0.762)
			(stroke
				(width 0.1524)
				(type default)
			)
			(layer "B.SilkS")
		)
		(fp_line
			(start -1.524 -0.762)
			(end -1.524 0.762)
			(stroke
				(width 0.1524)
				(type default)
			)
			(layer "B.SilkS")
		)
		(fp_line
			(start 1.1049 0.724916)
			(end -1.1049 0.724916)
			(stroke
				(width 0.1)
				(type default)
			)
			(layer "B.Fab")
		)
		(fp_line
			(start 1.1049 -0.724916)
			(end 1.1049 0.724916)
			(stroke
				(width 0.1)
				(type default)
			)
			(layer "B.Fab")
		)
		(fp_line
			(start -1.1049 0.724916)
			(end -1.1049 -0.724916)
			(stroke
				(width 0.1)
				(type default)
			)
			(layer "B.Fab")
		)
		(fp_line
			(start -1.1049 -0.724916)
			(end 1.1049 -0.724916)
			(stroke
				(width 0.1)
				(type default)
			)
			(layer "B.Fab")
		)
		(pad "1" smd rect
			(at 0.889 0 180)
			(size 1.016 1.27)
			(layers "B.Cu" "B.Mask" "B.Paste")
			(net "P12V_MEM_CPU0")
		)
		(pad "2" smd rect
			(at -0.889 0 180)
			(size 1.016 1.27)
			(layers "B.Cu" "B.Mask" "B.Paste")
			(net "GND")
		)
	)
	(footprint ""
		(layer "B.Cu")
		(at 412.367984 -192.660016 180)
		(property "Reference" "C157"
			(at 0 0 0)
			(layer "B.SilkS")
			(hide yes)
			(effects
				(font
					(size 1.27 1.27)
				)
				(justify mirror)
			)
		)
		(property "Value" ""
			(at 0 0 0)
			(layer "B.Fab")
			(effects
				(font
					(size 1.27 1.27)
				)
				(justify mirror)
			)
		)
		(duplicate_pad_numbers_are_jumpers no)
		(fp_line
			(start 1.524 0.762)
			(end 1.524 -0.762)
			(stroke
				(width 0.1524)
				(type default)
			)
			(layer "B.SilkS")
		)
		(fp_line
			(start 1.524 -0.762)
			(end -1.524 -0.762)
			(stroke
				(width 0.1524)
				(type default)
			)
			(layer "B.SilkS")
		)
		(fp_line
			(start -1.524 0.762)
			(end 1.524 0.762)
			(stroke
				(width 0.1524)
				(type default)
			)
			(layer "B.SilkS")
		)
		(fp_line
			(start -1.524 -0.762)
			(end -1.524 0.762)
			(stroke
				(width 0.1524)
				(type default)
			)
			(layer "B.SilkS")
		)
		(fp_line
			(start 1.1049 0.724916)
			(end -1.1049 0.724916)
			(stroke
				(width 0.1)
				(type default)
			)
			(layer "B.Fab")
		)
		(fp_line
			(start 1.1049 -0.724916)
			(end 1.1049 0.724916)
			(stroke
				(width 0.1)
				(type default)
			)
			(layer "B.Fab")
		)
		(fp_line
			(start -1.1049 0.724916)
			(end -1.1049 -0.724916)
			(stroke
				(width 0.1)
				(type default)
			)
			(layer "B.Fab")
		)
		(fp_line
			(start -1.1049 -0.724916)
			(end 1.1049 -0.724916)
			(stroke
				(width 0.1)
				(type default)
			)
			(layer "B.Fab")
		)
		(pad "1" smd rect
			(at 0.889 0 180)
			(size 1.016 1.27)
			(layers "B.Cu" "B.Mask" "B.Paste")
			(net "P12V_MEM_CPU0")
		)
		(pad "2" smd rect
			(at -0.889 0 180)
			(size 1.016 1.27)
			(layers "B.Cu" "B.Mask" "B.Paste")
			(net "GND")
		)
	)
	(footprint ""
		(layer "B.Cu")
		(at 199.941942 -344.270584)
		(property "Reference" "PC8001"
			(at 0 0 0)
			(layer "B.SilkS")
			(hide yes)
			(effects
				(font
					(size 1.27 1.27)
				)
				(justify mirror)
			)
		)
		(property "Value" ""
			(at 0 0 0)
			(layer "B.Fab")
			(effects
				(font
					(size 1.27 1.27)
				)
				(justify mirror)
			)
		)
		(duplicate_pad_numbers_are_jumpers no)
		(fp_line
			(start -1.524 -0.762)
			(end -1.524 0.762)
			(stroke
				(width 0.1524)
				(type default)
			)
			(layer "B.SilkS")
		)
		(fp_line
			(start -1.524 0.762)
			(end 1.524 0.762)
			(stroke
				(width 0.1524)
				(type default)
			)
			(layer "B.SilkS")
		)
		(fp_line
			(start 1.524 -0.762)
			(end -1.524 -0.762)
			(stroke
				(width 0.1524)
				(type default)
			)
			(layer "B.SilkS")
		)
		(fp_line
			(start 1.524 0.762)
			(end 1.524 -0.762)
			(stroke
				(width 0.1524)
				(type default)
			)
			(layer "B.SilkS")
		)
		(fp_line
			(start -1.1049 -0.724916)
			(end 1.1049 -0.724916)
			(stroke
				(width 0.1)
				(type default)
			)
			(layer "B.Fab")
		)
		(fp_line
			(start -1.1049 0.724916)
			(end -1.1049 -0.724916)
			(stroke
				(width 0.1)
				(type default)
			)
			(layer "B.Fab")
		)
		(fp_line
			(start 1.1049 -0.724916)
			(end 1.1049 0.724916)
			(stroke
				(width 0.1)
				(type default)
			)
			(layer "B.Fab")
		)
		(fp_line
			(start 1.1049 0.724916)
			(end -1.1049 0.724916)
			(stroke
				(width 0.1)
				(type default)
			)
			(layer "B.Fab")
		)
		(pad "1" smd rect
			(at 0.889 0)
			(size 1.016 1.27)
			(layers "B.Cu" "B.Mask" "B.Paste")
			(net "SW_P12V_AUX_PVDD_33_S5_FLT")
		)
		(pad "2" smd rect
			(at -0.889 0)
			(size 1.016 1.27)
			(layers "B.Cu" "B.Mask" "B.Paste")
			(net "GND")
		)
	)
	(footprint ""
		(layer "B.Cu")
		(at 391.72007 -181.684676 90)
		(property "Reference" "PR345"
			(at 0 0 90)
			(layer "B.SilkS")
			(hide yes)
			(effects
				(font
					(size 1.27 1.27)
				)
				(justify mirror)
			)
		)
		(property "Value" ""
			(at 0 0 90)
			(layer "B.Fab")
			(effects
				(font
					(size 1.27 1.27)
				)
				(justify mirror)
			)
		)
		(duplicate_pad_numbers_are_jumpers no)
		(fp_line
			(start 0.7874 -0.4064)
			(end -0.7874 -0.4064)
			(stroke
				(width 0.1524)
				(type default)
			)
			(layer "B.SilkS")
		)
		(fp_line
			(start -0.7874 -0.4064)
			(end -0.7874 0.4064)
			(stroke
				(width 0.1524)
				(type default)
			)
			(layer "B.SilkS")
		)
		(fp_line
			(start 0.7874 0.4064)
			(end 0.7874 -0.4064)
			(stroke
				(width 0.1524)
				(type default)
			)
			(layer "B.SilkS")
		)
		(fp_line
			(start -0.7874 0.4064)
			(end 0.7874 0.4064)
			(stroke
				(width 0.1524)
				(type default)
			)
			(layer "B.SilkS")
		)
		(fp_line
			(start 0.67945 -0.305054)
			(end 0.12065 -0.305054)
			(stroke
				(width 0.1)
				(type default)
			)
			(layer "B.Fab")
		)
		(fp_line
			(start 0.12065 -0.305054)
			(end 0.12065 -0.2794)
			(stroke
				(width 0.1)
				(type default)
			)
			(layer "B.Fab")
		)
		(fp_line
			(start -0.12065 -0.3048)
			(end -0.67945 -0.3048)
			(stroke
				(width 0.1)
				(type default)
			)
			(layer "B.Fab")
		)
		(fp_line
			(start -0.67945 -0.3048)
			(end -0.67945 0.3048)
			(stroke
				(width 0.1)
				(type default)
			)
			(layer "B.Fab")
		)
		(fp_line
			(start 0.12065 -0.2794)
			(end -0.12065 -0.2794)
			(stroke
				(width 0.1)
				(type default)
			)
			(layer "B.Fab")
		)
		(fp_line
			(start -0.12065 -0.2794)
			(end -0.12065 -0.3048)
			(stroke
				(width 0.1)
				(type default)
			)
			(layer "B.Fab")
		)
		(fp_line
			(start 0.12065 0.2794)
			(end 0.12065 0.3048)
			(stroke
				(width 0.1)
				(type default)
			)
			(layer "B.Fab")
		)
		(fp_line
			(start -0.120396 0.2794)
			(end 0.12065 0.2794)
			(stroke
				(width 0.1)
				(type default)
			)
			(layer "B.Fab")
		)
		(fp_line
			(start 0.67945 0.3048)
			(end 0.67945 -0.305054)
			(stroke
				(width 0.1)
				(type default)
			)
			(layer "B.Fab")
		)
		(fp_line
			(start 0.12065 0.3048)
			(end 0.67945 0.3048)
			(stroke
				(width 0.1)
				(type default)
			)
			(layer "B.Fab")
		)
		(fp_line
			(start -0.120396 0.3048)
			(end -0.120396 0.2794)
			(stroke
				(width 0.1)
				(type default)
			)
			(layer "B.Fab")
		)
		(fp_line
			(start -0.67945 0.3048)
			(end -0.120396 0.3048)
			(stroke
				(width 0.1)
				(type default)
			)
			(layer "B.Fab")
		)
		(pad "1" smd circle
			(at 0.40005 0 270)
			(size 0 0)
			(layers "B.Cu" "B.Mask" "B.Paste")
			(net "PVDDCR_CPU0_P0_PVCC")
		)
		(pad "2" smd circle
			(at -0.40005 0 270)
			(size 0 0)
			(layers "B.Cu" "B.Mask" "B.Paste")
			(net "PVDDCR_CPU0_P0_VCC4")
		)
	)
	(footprint ""
		(layer "B.Cu")
		(at 271.711928 -337.980528 -90)
		(property "Reference" "PC191_4"
			(at 0 0 90)
			(layer "B.SilkS")
			(hide yes)
			(effects
				(font
					(size 1.27 1.27)
				)
				(justify mirror)
			)
		)
		(property "Value" ""
			(at 0 0 90)
			(layer "B.Fab")
			(effects
				(font
					(size 1.27 1.27)
				)
				(justify mirror)
			)
		)
		(duplicate_pad_numbers_are_jumpers no)
		(fp_line
			(start -1.524 0.762)
			(end 1.524 0.762)
			(stroke
				(width 0.1524)
				(type default)
			)
			(layer "B.SilkS")
		)
		(fp_line
			(start 1.524 0.762)
			(end 1.524 -0.762)
			(stroke
				(width 0.1524)
				(type default)
			)
			(layer "B.SilkS")
		)
		(fp_line
			(start -1.524 -0.762)
			(end -1.524 0.762)
			(stroke
				(width 0.1524)
				(type default)
			)
			(layer "B.SilkS")
		)
		(fp_line
			(start 1.524 -0.762)
			(end -1.524 -0.762)
			(stroke
				(width 0.1524)
				(type default)
			)
			(layer "B.SilkS")
		)
		(fp_line
			(start -1.1049 0.724916)
			(end -1.1049 -0.724916)
			(stroke
				(width 0.1)
				(type default)
			)
			(layer "B.Fab")
		)
		(fp_line
			(start 1.1049 0.724916)
			(end -1.1049 0.724916)
			(stroke
				(width 0.1)
				(type default)
			)
			(layer "B.Fab")
		)
		(fp_line
			(start -1.1049 -0.724916)
			(end 1.1049 -0.724916)
			(stroke
				(width 0.1)
				(type default)
			)
			(layer "B.Fab")
		)
		(fp_line
			(start 1.1049 -0.724916)
			(end 1.1049 0.724916)
			(stroke
				(width 0.1)
				(type default)
			)
			(layer "B.Fab")
		)
		(pad "1" smd rect
			(at 0.889 0 270)
			(size 1.016 1.27)
			(layers "B.Cu" "B.Mask" "B.Paste")
			(net "PVDDIO_P0")
		)
		(pad "2" smd rect
			(at -0.889 0 270)
			(size 1.016 1.27)
			(layers "B.Cu" "B.Mask" "B.Paste")
			(net "GND")
		)
	)
)
